FILE_TYPE = CONNECTIVITY;
{Allegro Design Entry HDL 17.4-2019 S026 (4007227) 1/17/2022}
"PAGE_NUMBER" = 45;
0"NC";
1"M_I_CPU1_SA_DQ<31:0>";
2"M_I_CPU1_SB_DQ<31:0>";
3"M_I_CPU1_SA_CB<7:0>";
4"M_I_CPU1_SB_CB<7:0>";
5"M_I_CPU1_SA_DQS_DP<9:0>";
6"M_I_CPU1_SA_DQS_DN<9:0>";
7"M_I_CPU1_SB_DQS_DP<9:0>";
8"M_I_CPU1_SB_DQS_DN<9:0>";
9"M_I_CPU1_SA_CA<6:0>";
10"M_I_CPU1_SB_CA<6:0>";
11"M_I_CPU1_ALERT_N";
12"M_I_CPU1_ALERT_R_N";
13"TP_M_I_CPU1_SA_TEST39I";
14"M_I_CPU1_CLK_DP<0>";
15"M_I_CPU1_CLK_DN<0>";
16"M_I_CPU1_SA_CS_N<1>";
17"M_I_CPU1_SA_RSP<0>";
18"M_I_CPU1_SA_CS_N<0>";
19"M_I_CPU1_SA_PAR";
20"M_I_CPU1_SB_CS_N<0>";
21"M_I_CPU1_SB_CS_N<1>";
22"M_I_CPU1_SB_RSP<0>";
23"M_I_CPU1_SB_PAR";
24"M_I_CPU1_RESET_N";
25"M_I_CPU1_SB_DQS_DN<9>";
26"M_I_CPU1_SB_DQS_DN<8>";
27"M_I_CPU1_SB_CA<6>";
28"M_I_CPU1_SA_CA<6>";
29"M_I_CPU1_SB_CA<5>";
30"M_I_CPU1_SA_CA<5>";
31"M_I_CPU1_SB_CA<4>";
32"M_I_CPU1_SA_CA<4>";
33"M_I_CPU1_SB_CA<3>";
34"M_I_CPU1_SA_CA<3>";
35"M_I_CPU1_SB_CA<2>";
36"M_I_CPU1_SA_CA<2>";
37"M_I_CPU1_SB_CA<1>";
38"M_I_CPU1_SA_CA<1>";
39"M_I_CPU1_SB_CA<0>";
40"M_I_CPU1_SA_CA<0>";
41"M_I_CPU1_SB_DQS_DP<9>";
42"M_I_CPU1_SB_DQS_DN<7>";
43"M_I_CPU1_SB_DQS_DN<6>";
44"M_I_CPU1_SB_DQS_DN<5>";
45"M_I_CPU1_SB_DQS_DN<4>";
46"M_I_CPU1_SA_DQS_DN<9>";
47"M_I_CPU1_SB_DQS_DN<3>";
48"M_I_CPU1_SA_DQS_DN<8>";
49"M_I_CPU1_SB_DQS_DN<2>";
50"M_I_CPU1_SB_DQS_DN<1>";
51"M_I_CPU1_SB_DQS_DN<0>";
52"M_I_CPU1_SB_DQS_DP<8>";
53"M_I_CPU1_SB_DQS_DP<7>";
54"M_I_CPU1_SB_DQS_DP<6>";
55"M_I_CPU1_SB_DQS_DP<5>";
56"M_I_CPU1_SB_DQS_DP<4>";
57"M_I_CPU1_SB_DQS_DP<3>";
58"M_I_CPU1_SA_DQS_DP<9>";
59"M_I_CPU1_SB_DQS_DP<2>";
60"M_I_CPU1_SB_DQS_DP<1>";
61"M_I_CPU1_SB_DQS_DP<0>";
62"M_I_CPU1_SA_DQS_DN<4>";
63"M_I_CPU1_SA_DQS_DN<3>";
64"M_I_CPU1_SA_DQS_DN<2>";
65"M_I_CPU1_SA_DQS_DN<1>";
66"M_I_CPU1_SA_DQS_DN<0>";
67"M_I_CPU1_SA_DQS_DN<7>";
68"M_I_CPU1_SA_DQS_DN<6>";
69"M_I_CPU1_SA_DQS_DN<5>";
70"M_I_CPU1_SA_DQS_DP<8>";
71"M_I_CPU1_SA_DQS_DP<7>";
72"M_I_CPU1_SA_DQS_DP<6>";
73"M_I_CPU1_SA_DQS_DP<5>";
74"M_I_CPU1_SA_DQS_DP<4>";
75"M_I_CPU1_SA_DQS_DP<0>";
76"M_I_CPU1_SA_DQS_DP<3>";
77"M_I_CPU1_SA_DQS_DP<2>";
78"M_I_CPU1_SA_DQS_DP<1>";
79"M_I_CPU1_SB_CB<2>";
80"M_I_CPU1_SA_CB<7>";
81"M_I_CPU1_SB_CB<1>";
82"M_I_CPU1_SB_CB<0>";
83"M_I_CPU1_SB_CB<7>";
84"M_I_CPU1_SB_CB<6>";
85"M_I_CPU1_SB_CB<5>";
86"M_I_CPU1_SB_CB<4>";
87"M_I_CPU1_SB_CB<3>";
88"M_I_CPU1_SB_DQ<22>";
89"M_I_CPU1_SB_DQ<21>";
90"M_I_CPU1_SA_CB<6>";
91"M_I_CPU1_SB_DQ<20>";
92"M_I_CPU1_SB_DQ<31>";
93"M_I_CPU1_SA_CB<5>";
94"M_I_CPU1_SB_DQ<30>";
95"M_I_CPU1_SA_CB<4>";
96"M_I_CPU1_SA_CB<3>";
97"M_I_CPU1_SA_CB<2>";
98"M_I_CPU1_SA_CB<1>";
99"M_I_CPU1_SA_CB<0>";
100"M_I_CPU1_SB_DQ<29>";
101"M_I_CPU1_SB_DQ<28>";
102"M_I_CPU1_SB_DQ<27>";
103"M_I_CPU1_SB_DQ<26>";
104"M_I_CPU1_SB_DQ<25>";
105"M_I_CPU1_SB_DQ<24>";
106"M_I_CPU1_SB_DQ<23>";
107"M_I_CPU1_SB_DQ<5>";
108"M_I_CPU1_SB_DQ<11>";
109"M_I_CPU1_SB_DQ<4>";
110"M_I_CPU1_SB_DQ<10>";
111"M_I_CPU1_SB_DQ<3>";
112"M_I_CPU1_SB_DQ<2>";
113"M_I_CPU1_SB_DQ<19>";
114"M_I_CPU1_SB_DQ<18>";
115"M_I_CPU1_SB_DQ<17>";
116"M_I_CPU1_SB_DQ<16>";
117"M_I_CPU1_SB_DQ<9>";
118"M_I_CPU1_SB_DQ<15>";
119"M_I_CPU1_SB_DQ<8>";
120"M_I_CPU1_SB_DQ<14>";
121"M_I_CPU1_SB_DQ<7>";
122"M_I_CPU1_SB_DQ<13>";
123"M_I_CPU1_SB_DQ<6>";
124"M_I_CPU1_SB_DQ<12>";
125"M_I_CPU1_SA_DQ<17>";
126"M_I_CPU1_SA_DQ<28>";
127"M_I_CPU1_SA_DQ<16>";
128"M_I_CPU1_SA_DQ<27>";
129"M_I_CPU1_SA_DQ<26>";
130"M_I_CPU1_SA_DQ<25>";
131"M_I_CPU1_SA_DQ<24>";
132"M_I_CPU1_SB_DQ<1>";
133"M_I_CPU1_SA_DQ<23>";
134"M_I_CPU1_SB_DQ<0>";
135"M_I_CPU1_SA_DQ<22>";
136"M_I_CPU1_SA_DQ<21>";
137"M_I_CPU1_SA_DQ<20>";
138"M_I_CPU1_SA_DQ<31>";
139"M_I_CPU1_SA_DQ<30>";
140"M_I_CPU1_SA_DQ<19>";
141"M_I_CPU1_SA_DQ<18>";
142"M_I_CPU1_SA_DQ<29>";
143"M_I_CPU1_SA_DQ<5>";
144"M_I_CPU1_SA_DQ<4>";
145"M_I_CPU1_SA_DQ<3>";
146"M_I_CPU1_SA_DQ<15>";
147"M_I_CPU1_SA_DQ<2>";
148"M_I_CPU1_SA_DQ<14>";
149"M_I_CPU1_SA_DQ<1>";
150"M_I_CPU1_SA_DQ<13>";
151"M_I_CPU1_SA_DQ<0>";
152"M_I_CPU1_SA_DQ<12>";
153"M_I_CPU1_SA_DQ<11>";
154"M_I_CPU1_SA_DQ<10>";
155"M_I_CPU1_SA_DQ<9>";
156"M_I_CPU1_SA_DQ<8>";
157"M_I_CPU1_SA_DQ<7>";
158"M_I_CPU1_SA_DQ<6>";
%"GENOA_SP5"
"9","(-4500,3575)","0","pure_quanta","I159";
;
LOCATION"U26"
$SEC"9"
CDS_SEC"9"
PART_TYPE"SMLF"
MATERIAL"IO"
VALUE"SOCKET6096_13568-001"
NEEDS_NO_SIZE"TRUE"
CDS_LMAN_SYM_OUTLINE"-650,2525,650,-2525"
CDS_LIB"pure_quanta"
PART_NUMBER"DGA^6000030";
"TEST39I"
$PN"BF21"13;
"MIA_DATA5"
$PN"K21"143;
"MIA_DATA17"
$PN"V21"125;
"MIA_DATA28"
$PN"AG19"126;
"MIA_DQS_H0"
$PN"G19"75;
"MIA_DQS_L4"
$PN"AM20"62;
"MIB_CHECK2"
$PN"CA19"79;
"MIB_DATA5"
$PN"CG21"107;
"MIB_DATA11"
$PN"CK21"108;
"MIB_DATA22"
$PN"CW19"88;
"MI_ALERT_L"
$PN"AT21"12;
"MIA0_RSP_L"
$PN"BN21"17;
"MIA1_RSP_L"
$PN"BP21"0;
"MIA_CHECK7"
$PN"AR21"80;
"MIA_DATA4"
$PN"J19"144;
"MIA_DATA16"
$PN"U19"127;
"MIA_DATA27"
$PN"AE21"128;
"MIA_DQS_L3"
$PN"AF20"63;
"MIB_CHECK1"
$PN"CA21"81;
"MIB_DATA4"
$PN"CF20"109;
"MIB_DATA10"
$PN"CJ19"110;
"MIB_DATA21"
$PN"CW21"89;
"MIB_PAR"
$PN"BL21"23;
"MIA_CHECK6"
$PN"AP20"90;
"MIA_DATA3"
$PN"G21"145;
"MIA_DATA15"
$PN"U21"146;
"MIA_DATA26"
$PN"AD20"129;
"MIA_DQS_L2"
$PN"Y20"64;
"MIA_PAR"
$PN"BC21"19;
"MIB1_CS_L1"
$PN"BM20"0;
"MIB_CHECK0"
$PN"BY20"82;
"MIB_DATA3"
$PN"CD21"111;
"MIB_DATA20"
$PN"CV20"91;
"MIB_DATA31"
$PN"DF21"92;
"MIB_DQS_H9"
$PN"BV20"41;
"MIA_CHECK5"
$PN"AP21"93;
"MIA_DATA2"
$PN"F20"147;
"MIA_DATA14"
$PN"T20"148;
"MIA_DATA25"
$PN"AD21"130;
"MIA_DQS_L1"
$PN"P20"65;
"MIB0_CS_L1"
$PN"BN19"21;
"MIB1_CS_L0"
$PN"BL19"0;
"MIB_DATA2"
$PN"CC19"112;
"MIB_DATA30"
$PN"DE19"94;
"MIB_DQS_H8"
$PN"DD21"52;
"MIA_CHECK4"
$PN"AN19"95;
"MIA_DATA1"
$PN"F21"149;
"MIA_DATA13"
$PN"T21"150;
"MIA_DATA24"
$PN"AC19"131;
"MIA_DQS_L0"
$PN"H20"66;
"MIB0_CS_L0"
$PN"BM21"20;
"MIB_DATA1"
$PN"CC21"132;
"MIB_DQS_H7"
$PN"CV21"53;
"MIA_CHECK3"
$PN"AL21"96;
"MIA_DATA0"
$PN"E19"151;
"MIA_DATA12"
$PN"R19"152;
"MIA_DATA23"
$PN"AC21"133;
"MIB_DATA0"
$PN"CB20"134;
"MIB_DQS_H6"
$PN"CM21"54;
"MI_RESET_L"
$PN"AU21"24;
"MI0_CLK_L"
$PN"BD20"15;
"MI1_CLK_L"
$PN"BG19"0;
"MIA_CHECK2"
$PN"AK20"97;
"MIA_DATA11"
$PN"N21"153;
"MIA_DATA22"
$PN"AB20"135;
"MIB_DQS_H5"
$PN"CF21"55;
"MIB_DQS_L9"
$PN"BW19"25;
"MIA_CHECK1"
$PN"AK21"98;
"MIA_DATA10"
$PN"M20"154;
"MIA_DATA21"
$PN"AB21"136;
"MIB_DQS_H4"
$PN"BY21"56;
"MIB_DQS_L8"
$PN"DC21"26;
"MIA_CHECK0"
$PN"AJ19"99;
"MIA_DATA20"
$PN"AA19"137;
"MIA_DATA31"
$PN"AJ21"138;
"MIA_DQS_H9"
$PN"AN21"58;
"MIB_CA6"
$PN"BK20"27;
"MIB_DQS_H3"
$PN"DB20"57;
"MIB_DQS_L7"
$PN"CU21"42;
"MIA0_CS_L1"
$PN"AV21"16;
"MIA1_CS_L1"
$PN"AW21"0;
"MIA_CA6"
$PN"BB21"28;
"MIA_DATA30"
$PN"AH20"139;
"MIA_DQS_H8"
$PN"AG21"70;
"MIB_CA5"
$PN"BK21"29;
"MIB_DATA19"
$PN"CT21"113;
"MIB_DQS_H2"
$PN"CT20"59;
"MIB_DQS_L6"
$PN"CL21"43;
"MI0_CLK_H"
$PN"BC19"14;
"MI1_CLK_H"
$PN"BF20"0;
"MIA0_CS_L0"
$PN"AU19"18;
"MIA1_CS_L0"
$PN"AV20"0;
"MIA_CA5"
$PN"BB20"30;
"MIA_DQS_H7"
$PN"AA21"71;
"MIB_CA4"
$PN"BJ21"31;
"MIB_DATA18"
$PN"CR19"114;
"MIB_DATA29"
$PN"DE21"100;
"MIB_DQS_H1"
$PN"CK20"60;
"MIB_DQS_L5"
$PN"CE21"44;
"MIA_CA4"
$PN"BA19"32;
"MIA_DQS_H6"
$PN"R21"72;
"MIB1_RSP_L"
$PN"BR19"0;
"MIB_CA3"
$PN"BJ19"33;
"MIB_DATA17"
$PN"CR21"115;
"MIB_DATA28"
$PN"DD20"101;
"MIB_DQS_H0"
$PN"CD20"61;
"MIB_DQS_L4"
$PN"BW21"45;
"MIA_CA3"
$PN"BA21"34;
"MIA_DQS_H5"
$PN"J21"73;
"MIA_DQS_L9"
$PN"AM21"46;
"MIB0_RSP_L"
$PN"BP20"22;
"MIB_CA2"
$PN"BH20"35;
"MIB_CHECK7"
$PN"BV21"83;
"MIB_DATA16"
$PN"CP20"116;
"MIB_DATA27"
$PN"DB21"102;
"MIB_DQS_L3"
$PN"DC19"47;
"MIA_CA2"
$PN"AY21"36;
"MIA_DATA9"
$PN"M21"155;
"MIA_DQS_H4"
$PN"AL19"74;
"MIA_DQS_L8"
$PN"AF21"48;
"MIB_CA1"
$PN"BH21"37;
"MIB_CHECK6"
$PN"BU19"84;
"MIB_DATA9"
$PN"CJ21"117;
"MIB_DATA15"
$PN"CP21"118;
"MIB_DATA26"
$PN"DA19"103;
"MIB_DQS_L2"
$PN"CU19"49;
"MIA_CA1"
$PN"AY20"38;
"MIA_DATA8"
$PN"L19"156;
"MIA_DQS_H3"
$PN"AE19"76;
"MIA_DQS_L7"
$PN"Y21"67;
"MIB_CA0"
$PN"BG21"39;
"MIB_CHECK5"
$PN"BU21"85;
"MIB_DATA8"
$PN"CH20"119;
"MIB_DATA14"
$PN"CN19"120;
"MIB_DATA25"
$PN"DA21"104;
"MIB_DQS_L1"
$PN"CL19"50;
"MIA_CA0"
$PN"AW19"40;
"MIA_DATA7"
$PN"L21"157;
"MIA_DATA19"
$PN"W21"140;
"MIA_DQS_H2"
$PN"W19"77;
"MIA_DQS_L6"
$PN"P21"68;
"MIB_CHECK4"
$PN"BT20"86;
"MIB_DATA7"
$PN"CH21"121;
"MIB_DATA13"
$PN"CN21"122;
"MIB_DATA24"
$PN"CY20"105;
"MIB_DQS_L0"
$PN"CE19"51;
"MIA_DATA6"
$PN"K20"158;
"MIA_DATA18"
$PN"V20"141;
"MIA_DATA29"
$PN"AH21"142;
"MIA_DQS_H1"
$PN"N19"78;
"MIA_DQS_L5"
$PN"H21"69;
"MIB_CHECK3"
$PN"CB21"87;
"MIB_DATA6"
$PN"CG19"123;
"MIB_DATA12"
$PN"CM20"124;
"MIB_DATA23"
$PN"CY21"106;
%"TAP"
"1","(-3225,5900)","0","mstr_standard","I162";
;
CDS_LIB"mstr_standard"
BODY_TYPE"PLUMBING"
HDL_TAP"TRUE";
"B \NAC \NWC"1;
"S \NAC"
BN"1"149;
%"TAP"
"1","(-3225,5950)","0","mstr_standard","I163";
;
CDS_LIB"mstr_standard"
BODY_TYPE"PLUMBING"
HDL_TAP"TRUE";
"B \NAC \NWC"1;
"S \NAC"
BN"0"151;
%"TAP"
"1","(-3225,5800)","0","mstr_standard","I164";
;
CDS_LIB"mstr_standard"
BODY_TYPE"PLUMBING"
HDL_TAP"TRUE";
"B \NAC \NWC"1;
"S \NAC"
BN"3"145;
%"TAP"
"1","(-3225,5850)","0","mstr_standard","I165";
;
CDS_LIB"mstr_standard"
BODY_TYPE"PLUMBING"
HDL_TAP"TRUE";
"B \NAC \NWC"1;
"S \NAC"
BN"2"147;
%"TAP"
"1","(-3225,5750)","0","mstr_standard","I166";
;
CDS_LIB"mstr_standard"
BODY_TYPE"PLUMBING"
HDL_TAP"TRUE";
"B \NAC \NWC"1;
"S \NAC"
BN"4"144;
%"TAP"
"1","(-3225,5650)","0","mstr_standard","I167";
;
CDS_LIB"mstr_standard"
BODY_TYPE"PLUMBING"
HDL_TAP"TRUE";
"B \NAC \NWC"1;
"S \NAC"
BN"6"158;
%"TAP"
"1","(-3225,5700)","0","mstr_standard","I168";
;
CDS_LIB"mstr_standard"
BODY_TYPE"PLUMBING"
HDL_TAP"TRUE";
"B \NAC \NWC"1;
"S \NAC"
BN"5"143;
%"TAP"
"1","(-3225,5500)","0","mstr_standard","I169";
;
CDS_LIB"mstr_standard"
BODY_TYPE"PLUMBING"
HDL_TAP"TRUE";
"B \NAC \NWC"1;
"S \NAC"
BN"8"156;
%"TAP"
"1","(-3225,5600)","0","mstr_standard","I170";
;
CDS_LIB"mstr_standard"
BODY_TYPE"PLUMBING"
HDL_TAP"TRUE";
"B \NAC \NWC"1;
"S \NAC"
BN"7"157;
%"TAP"
"1","(-3225,5400)","0","mstr_standard","I171";
;
CDS_LIB"mstr_standard"
BODY_TYPE"PLUMBING"
HDL_TAP"TRUE";
"B \NAC \NWC"1;
"S \NAC"
BN"10"154;
%"TAP"
"1","(-3225,5450)","0","mstr_standard","I172";
;
CDS_LIB"mstr_standard"
BODY_TYPE"PLUMBING"
HDL_TAP"TRUE";
"B \NAC \NWC"1;
"S \NAC"
BN"9"155;
%"TAP"
"1","(-3225,5250)","0","mstr_standard","I173";
;
CDS_LIB"mstr_standard"
BODY_TYPE"PLUMBING"
HDL_TAP"TRUE";
"B \NAC \NWC"1;
"S \NAC"
BN"13"150;
%"TAP"
"1","(-3225,5300)","0","mstr_standard","I174";
;
CDS_LIB"mstr_standard"
BODY_TYPE"PLUMBING"
HDL_TAP"TRUE";
"B \NAC \NWC"1;
"S \NAC"
BN"12"152;
%"TAP"
"1","(-3225,5350)","0","mstr_standard","I175";
;
CDS_LIB"mstr_standard"
BODY_TYPE"PLUMBING"
HDL_TAP"TRUE";
"B \NAC \NWC"1;
"S \NAC"
BN"11"153;
%"TAP"
"1","(-3225,5200)","0","mstr_standard","I176";
;
CDS_LIB"mstr_standard"
BODY_TYPE"PLUMBING"
HDL_TAP"TRUE";
"B \NAC \NWC"1;
"S \NAC"
BN"14"148;
%"TAP"
"1","(-3225,5150)","0","mstr_standard","I177";
;
CDS_LIB"mstr_standard"
BODY_TYPE"PLUMBING"
HDL_TAP"TRUE";
"B \NAC \NWC"1;
"S \NAC"
BN"15"146;
%"TAP"
"1","(-3225,5050)","0","mstr_standard","I178";
;
CDS_LIB"mstr_standard"
BODY_TYPE"PLUMBING"
HDL_TAP"TRUE";
"B \NAC \NWC"1;
"S \NAC"
BN"16"127;
%"TAP"
"1","(-3225,5000)","0","mstr_standard","I179";
;
CDS_LIB"mstr_standard"
BODY_TYPE"PLUMBING"
HDL_TAP"TRUE";
"B \NAC \NWC"1;
"S \NAC"
BN"17"125;
%"TAP"
"1","(-3225,4900)","0","mstr_standard","I180";
;
CDS_LIB"mstr_standard"
BODY_TYPE"PLUMBING"
HDL_TAP"TRUE";
"B \NAC \NWC"1;
"S \NAC"
BN"19"140;
%"TAP"
"1","(-3225,4950)","0","mstr_standard","I181";
;
CDS_LIB"mstr_standard"
BODY_TYPE"PLUMBING"
HDL_TAP"TRUE";
"B \NAC \NWC"1;
"S \NAC"
BN"18"141;
%"TAP"
"1","(-3225,4850)","0","mstr_standard","I182";
;
CDS_LIB"mstr_standard"
BODY_TYPE"PLUMBING"
HDL_TAP"TRUE";
"B \NAC \NWC"1;
"S \NAC"
BN"20"137;
%"TAP"
"1","(-3225,4750)","0","mstr_standard","I183";
;
CDS_LIB"mstr_standard"
BODY_TYPE"PLUMBING"
HDL_TAP"TRUE";
"B \NAC \NWC"1;
"S \NAC"
BN"22"135;
%"TAP"
"1","(-3225,4800)","0","mstr_standard","I184";
;
CDS_LIB"mstr_standard"
BODY_TYPE"PLUMBING"
HDL_TAP"TRUE";
"B \NAC \NWC"1;
"S \NAC"
BN"21"136;
%"TAP"
"1","(-3225,4700)","0","mstr_standard","I185";
;
CDS_LIB"mstr_standard"
BODY_TYPE"PLUMBING"
HDL_TAP"TRUE";
"B \NAC \NWC"1;
"S \NAC"
BN"23"133;
%"TAP"
"1","(-3225,4500)","0","mstr_standard","I186";
;
CDS_LIB"mstr_standard"
BODY_TYPE"PLUMBING"
HDL_TAP"TRUE";
"B \NAC \NWC"1;
"S \NAC"
BN"26"129;
%"TAP"
"1","(-3225,4600)","0","mstr_standard","I187";
;
CDS_LIB"mstr_standard"
BODY_TYPE"PLUMBING"
HDL_TAP"TRUE";
"B \NAC \NWC"1;
"S \NAC"
BN"24"131;
%"TAP"
"1","(-3225,4550)","0","mstr_standard","I188";
;
CDS_LIB"mstr_standard"
BODY_TYPE"PLUMBING"
HDL_TAP"TRUE";
"B \NAC \NWC"1;
"S \NAC"
BN"25"130;
%"TAP"
"1","(-3225,4400)","0","mstr_standard","I189";
;
CDS_LIB"mstr_standard"
BODY_TYPE"PLUMBING"
HDL_TAP"TRUE";
"B \NAC \NWC"1;
"S \NAC"
BN"28"126;
%"TAP"
"1","(-3225,4450)","0","mstr_standard","I190";
;
CDS_LIB"mstr_standard"
BODY_TYPE"PLUMBING"
HDL_TAP"TRUE";
"B \NAC \NWC"1;
"S \NAC"
BN"27"128;
%"TAP"
"1","(-3225,4350)","0","mstr_standard","I191";
;
CDS_LIB"mstr_standard"
BODY_TYPE"PLUMBING"
HDL_TAP"TRUE";
"B \NAC \NWC"1;
"S \NAC"
BN"29"142;
%"TAP"
"1","(-3225,4300)","0","mstr_standard","I192";
;
CDS_LIB"mstr_standard"
BODY_TYPE"PLUMBING"
HDL_TAP"TRUE";
"B \NAC \NWC"1;
"S \NAC"
BN"30"139;
%"TAP"
"1","(-3225,4250)","0","mstr_standard","I193";
;
CDS_LIB"mstr_standard"
BODY_TYPE"PLUMBING"
HDL_TAP"TRUE";
"B \NAC \NWC"1;
"S \NAC"
BN"31"138;
%"TAP"
"1","(-3225,4150)","0","mstr_standard","I194";
;
CDS_LIB"mstr_standard"
BODY_TYPE"PLUMBING"
HDL_TAP"TRUE";
"B \NAC \NWC"2;
"S \NAC"
BN"0"134;
%"TAP"
"1","(-3225,4100)","0","mstr_standard","I195";
;
CDS_LIB"mstr_standard"
BODY_TYPE"PLUMBING"
HDL_TAP"TRUE";
"B \NAC \NWC"2;
"S \NAC"
BN"1"132;
%"TAP"
"1","(-3225,4050)","0","mstr_standard","I197";
;
CDS_LIB"mstr_standard"
BODY_TYPE"PLUMBING"
HDL_TAP"TRUE";
"B \NAC \NWC"2;
"S \NAC"
BN"2"112;
%"TAP"
"1","(-3225,4000)","0","mstr_standard","I198";
;
CDS_LIB"mstr_standard"
BODY_TYPE"PLUMBING"
HDL_TAP"TRUE";
"B \NAC \NWC"2;
"S \NAC"
BN"3"111;
%"TAP"
"1","(-3225,3950)","0","mstr_standard","I199";
;
CDS_LIB"mstr_standard"
BODY_TYPE"PLUMBING"
HDL_TAP"TRUE";
"B \NAC \NWC"2;
"S \NAC"
BN"4"109;
%"TAP"
"1","(-3225,3900)","0","mstr_standard","I200";
;
CDS_LIB"mstr_standard"
BODY_TYPE"PLUMBING"
HDL_TAP"TRUE";
"B \NAC \NWC"2;
"S \NAC"
BN"5"107;
%"TAP"
"1","(-3225,3850)","0","mstr_standard","I201";
;
CDS_LIB"mstr_standard"
BODY_TYPE"PLUMBING"
HDL_TAP"TRUE";
"B \NAC \NWC"2;
"S \NAC"
BN"6"123;
%"TAP"
"1","(-3225,3800)","0","mstr_standard","I202";
;
CDS_LIB"mstr_standard"
BODY_TYPE"PLUMBING"
HDL_TAP"TRUE";
"B \NAC \NWC"2;
"S \NAC"
BN"7"121;
%"TAP"
"1","(-3225,3700)","0","mstr_standard","I203";
;
CDS_LIB"mstr_standard"
BODY_TYPE"PLUMBING"
HDL_TAP"TRUE";
"B \NAC \NWC"2;
"S \NAC"
BN"8"119;
%"TAP"
"1","(-3225,3650)","0","mstr_standard","I204";
;
CDS_LIB"mstr_standard"
BODY_TYPE"PLUMBING"
HDL_TAP"TRUE";
"B \NAC \NWC"2;
"S \NAC"
BN"9"117;
%"TAP"
"1","(-3225,3600)","0","mstr_standard","I205";
;
CDS_LIB"mstr_standard"
BODY_TYPE"PLUMBING"
HDL_TAP"TRUE";
"B \NAC \NWC"2;
"S \NAC"
BN"10"110;
%"TAP"
"1","(-3225,3550)","0","mstr_standard","I206";
;
CDS_LIB"mstr_standard"
BODY_TYPE"PLUMBING"
HDL_TAP"TRUE";
"B \NAC \NWC"2;
"S \NAC"
BN"11"108;
%"TAP"
"1","(-3225,3500)","0","mstr_standard","I207";
;
CDS_LIB"mstr_standard"
BODY_TYPE"PLUMBING"
HDL_TAP"TRUE";
"B \NAC \NWC"2;
"S \NAC"
BN"12"124;
%"TAP"
"1","(-3225,3450)","0","mstr_standard","I208";
;
CDS_LIB"mstr_standard"
BODY_TYPE"PLUMBING"
HDL_TAP"TRUE";
"B \NAC \NWC"2;
"S \NAC"
BN"13"122;
%"TAP"
"1","(-3225,3350)","0","mstr_standard","I209";
;
CDS_LIB"mstr_standard"
BODY_TYPE"PLUMBING"
HDL_TAP"TRUE";
"B \NAC \NWC"2;
"S \NAC"
BN"15"118;
%"TAP"
"1","(-3225,3400)","0","mstr_standard","I210";
;
CDS_LIB"mstr_standard"
BODY_TYPE"PLUMBING"
HDL_TAP"TRUE";
"B \NAC \NWC"2;
"S \NAC"
BN"14"120;
%"TAP"
"1","(-3225,3250)","0","mstr_standard","I211";
;
CDS_LIB"mstr_standard"
BODY_TYPE"PLUMBING"
HDL_TAP"TRUE";
"B \NAC \NWC"2;
"S \NAC"
BN"16"116;
%"TAP"
"1","(-3225,3200)","0","mstr_standard","I212";
;
CDS_LIB"mstr_standard"
BODY_TYPE"PLUMBING"
HDL_TAP"TRUE";
"B \NAC \NWC"2;
"S \NAC"
BN"17"115;
%"TAP"
"1","(-3225,3150)","0","mstr_standard","I213";
;
CDS_LIB"mstr_standard"
BODY_TYPE"PLUMBING"
HDL_TAP"TRUE";
"B \NAC \NWC"2;
"S \NAC"
BN"18"114;
%"TAP"
"1","(-3225,3100)","0","mstr_standard","I214";
;
CDS_LIB"mstr_standard"
BODY_TYPE"PLUMBING"
HDL_TAP"TRUE";
"B \NAC \NWC"2;
"S \NAC"
BN"19"113;
%"TAP"
"1","(-3225,3000)","0","mstr_standard","I215";
;
CDS_LIB"mstr_standard"
BODY_TYPE"PLUMBING"
HDL_TAP"TRUE";
"B \NAC \NWC"2;
"S \NAC"
BN"21"89;
%"TAP"
"1","(-3225,2900)","0","mstr_standard","I216";
;
CDS_LIB"mstr_standard"
BODY_TYPE"PLUMBING"
HDL_TAP"TRUE";
"B \NAC \NWC"2;
"S \NAC"
BN"23"106;
%"TAP"
"1","(-3225,3050)","0","mstr_standard","I217";
;
CDS_LIB"mstr_standard"
BODY_TYPE"PLUMBING"
HDL_TAP"TRUE";
"B \NAC \NWC"2;
"S \NAC"
BN"20"91;
%"TAP"
"1","(-3225,2950)","0","mstr_standard","I218";
;
CDS_LIB"mstr_standard"
BODY_TYPE"PLUMBING"
HDL_TAP"TRUE";
"B \NAC \NWC"2;
"S \NAC"
BN"22"88;
%"TAP"
"1","(-3225,2800)","0","mstr_standard","I219";
;
CDS_LIB"mstr_standard"
BODY_TYPE"PLUMBING"
HDL_TAP"TRUE";
"B \NAC \NWC"2;
"S \NAC"
BN"24"105;
%"TAP"
"1","(-3225,2750)","0","mstr_standard","I220";
;
CDS_LIB"mstr_standard"
BODY_TYPE"PLUMBING"
HDL_TAP"TRUE";
"B \NAC \NWC"2;
"S \NAC"
BN"25"104;
%"TAP"
"1","(-3225,2700)","0","mstr_standard","I221";
;
CDS_LIB"mstr_standard"
BODY_TYPE"PLUMBING"
HDL_TAP"TRUE";
"B \NAC \NWC"2;
"S \NAC"
BN"26"103;
%"TAP"
"1","(-3225,2600)","0","mstr_standard","I222";
;
CDS_LIB"mstr_standard"
BODY_TYPE"PLUMBING"
HDL_TAP"TRUE";
"B \NAC \NWC"2;
"S \NAC"
BN"28"101;
%"TAP"
"1","(-3225,2650)","0","mstr_standard","I223";
;
CDS_LIB"mstr_standard"
BODY_TYPE"PLUMBING"
HDL_TAP"TRUE";
"B \NAC \NWC"2;
"S \NAC"
BN"27"102;
%"TAP"
"1","(-3225,2500)","0","mstr_standard","I224";
;
CDS_LIB"mstr_standard"
BODY_TYPE"PLUMBING"
HDL_TAP"TRUE";
"B \NAC \NWC"2;
"S \NAC"
BN"30"94;
%"TAP"
"1","(-3225,2550)","0","mstr_standard","I225";
;
CDS_LIB"mstr_standard"
BODY_TYPE"PLUMBING"
HDL_TAP"TRUE";
"B \NAC \NWC"2;
"S \NAC"
BN"29"100;
%"TAP"
"1","(-3225,2450)","0","mstr_standard","I226";
;
CDS_LIB"mstr_standard"
BODY_TYPE"PLUMBING"
HDL_TAP"TRUE";
"B \NAC \NWC"2;
"S \NAC"
BN"31"92;
%"TAP"
"1","(-3225,2350)","0","mstr_standard","I227";
;
CDS_LIB"mstr_standard"
BODY_TYPE"PLUMBING"
HDL_TAP"TRUE";
"B \NAC \NWC"3;
"S \NAC"
BN"0"99;
%"TAP"
"1","(-3225,2300)","0","mstr_standard","I228";
;
CDS_LIB"mstr_standard"
BODY_TYPE"PLUMBING"
HDL_TAP"TRUE";
"B \NAC \NWC"3;
"S \NAC"
BN"1"98;
%"TAP"
"1","(-3225,2200)","0","mstr_standard","I229";
;
CDS_LIB"mstr_standard"
BODY_TYPE"PLUMBING"
HDL_TAP"TRUE";
"B \NAC \NWC"3;
"S \NAC"
BN"3"96;
%"TAP"
"1","(-3225,2250)","0","mstr_standard","I230";
;
CDS_LIB"mstr_standard"
BODY_TYPE"PLUMBING"
HDL_TAP"TRUE";
"B \NAC \NWC"3;
"S \NAC"
BN"2"97;
%"TAP"
"1","(-3225,2050)","0","mstr_standard","I231";
;
CDS_LIB"mstr_standard"
BODY_TYPE"PLUMBING"
HDL_TAP"TRUE";
"B \NAC \NWC"3;
"S \NAC"
BN"6"90;
%"TAP"
"1","(-3225,2100)","0","mstr_standard","I232";
;
CDS_LIB"mstr_standard"
BODY_TYPE"PLUMBING"
HDL_TAP"TRUE";
"B \NAC \NWC"3;
"S \NAC"
BN"5"93;
%"TAP"
"1","(-3225,2150)","0","mstr_standard","I233";
;
CDS_LIB"mstr_standard"
BODY_TYPE"PLUMBING"
HDL_TAP"TRUE";
"B \NAC \NWC"3;
"S \NAC"
BN"4"95;
%"TAP"
"1","(-3225,1900)","0","mstr_standard","I235";
;
CDS_LIB"mstr_standard"
BODY_TYPE"PLUMBING"
HDL_TAP"TRUE";
"B \NAC \NWC"4;
"S \NAC"
BN"0"82;
%"TAP"
"1","(-3225,2000)","0","mstr_standard","I236";
;
CDS_LIB"mstr_standard"
BODY_TYPE"PLUMBING"
HDL_TAP"TRUE";
"B \NAC \NWC"3;
"S \NAC"
BN"7"80;
%"TAP"
"1","(-3225,1800)","0","mstr_standard","I237";
;
CDS_LIB"mstr_standard"
BODY_TYPE"PLUMBING"
HDL_TAP"TRUE";
"B \NAC \NWC"4;
"S \NAC"
BN"2"79;
%"TAP"
"1","(-3225,1850)","0","mstr_standard","I238";
;
CDS_LIB"mstr_standard"
BODY_TYPE"PLUMBING"
HDL_TAP"TRUE";
"B \NAC \NWC"4;
"S \NAC"
BN"1"81;
%"TAP"
"1","(-3225,1750)","0","mstr_standard","I239";
;
CDS_LIB"mstr_standard"
BODY_TYPE"PLUMBING"
HDL_TAP"TRUE";
"B \NAC \NWC"4;
"S \NAC"
BN"3"87;
%"TAP"
"1","(-3225,1700)","0","mstr_standard","I240";
;
CDS_LIB"mstr_standard"
BODY_TYPE"PLUMBING"
HDL_TAP"TRUE";
"B \NAC \NWC"4;
"S \NAC"
BN"4"86;
%"TAP"
"1","(-3225,1650)","0","mstr_standard","I241";
;
CDS_LIB"mstr_standard"
BODY_TYPE"PLUMBING"
HDL_TAP"TRUE";
"B \NAC \NWC"4;
"S \NAC"
BN"5"85;
%"TAP"
"1","(-3225,1550)","0","mstr_standard","I242";
;
CDS_LIB"mstr_standard"
BODY_TYPE"PLUMBING"
HDL_TAP"TRUE";
"B \NAC \NWC"4;
"S \NAC"
BN"7"83;
%"TAP"
"1","(-3225,1600)","0","mstr_standard","I243";
;
CDS_LIB"mstr_standard"
BODY_TYPE"PLUMBING"
HDL_TAP"TRUE";
"B \NAC \NWC"4;
"S \NAC"
BN"6"84;
%"TAP"
"1","(-5650,5950)","2","mstr_standard","I244";
;
CDS_LIB"mstr_standard"
BODY_TYPE"PLUMBING"
HDL_TAP"TRUE";
"B \NAC \NWC"5;
"S \NAC"
BN"0"75;
%"TAP"
"1","(-5650,5850)","2","mstr_standard","I245";
;
CDS_LIB"mstr_standard"
BODY_TYPE"PLUMBING"
HDL_TAP"TRUE";
"B \NAC \NWC"5;
"S \NAC"
BN"1"78;
%"TAP"
"1","(-5650,5750)","2","mstr_standard","I246";
;
CDS_LIB"mstr_standard"
BODY_TYPE"PLUMBING"
HDL_TAP"TRUE";
"B \NAC \NWC"5;
"S \NAC"
BN"2"77;
%"TAP"
"1","(-5650,5650)","2","mstr_standard","I247";
;
CDS_LIB"mstr_standard"
BODY_TYPE"PLUMBING"
HDL_TAP"TRUE";
"B \NAC \NWC"5;
"S \NAC"
BN"3"76;
%"TAP"
"1","(-5650,5450)","2","mstr_standard","I248";
;
CDS_LIB"mstr_standard"
BODY_TYPE"PLUMBING"
HDL_TAP"TRUE";
"B \NAC \NWC"5;
"S \NAC"
BN"5"73;
%"TAP"
"1","(-5650,5550)","2","mstr_standard","I249";
;
CDS_LIB"mstr_standard"
BODY_TYPE"PLUMBING"
HDL_TAP"TRUE";
"B \NAC \NWC"5;
"S \NAC"
BN"4"74;
%"TAP"
"1","(-5650,5350)","2","mstr_standard","I250";
;
CDS_LIB"mstr_standard"
BODY_TYPE"PLUMBING"
HDL_TAP"TRUE";
"B \NAC \NWC"5;
"S \NAC"
BN"6"72;
%"TAP"
"1","(-5650,5250)","2","mstr_standard","I251";
;
CDS_LIB"mstr_standard"
BODY_TYPE"PLUMBING"
HDL_TAP"TRUE";
"B \NAC \NWC"5;
"S \NAC"
BN"7"71;
%"TAP"
"1","(-5650,5150)","2","mstr_standard","I252";
;
CDS_LIB"mstr_standard"
BODY_TYPE"PLUMBING"
HDL_TAP"TRUE";
"B \NAC \NWC"5;
"S \NAC"
BN"8"70;
%"TAP"
"1","(-5850,5900)","2","mstr_standard","I253";
;
CDS_LIB"mstr_standard"
BODY_TYPE"PLUMBING"
HDL_TAP"TRUE";
"B \NAC \NWC"6;
"S \NAC"
BN"0"66;
%"TAP"
"1","(-5850,5700)","2","mstr_standard","I254";
;
CDS_LIB"mstr_standard"
BODY_TYPE"PLUMBING"
HDL_TAP"TRUE";
"B \NAC \NWC"6;
"S \NAC"
BN"2"64;
%"TAP"
"1","(-5850,5800)","2","mstr_standard","I255";
;
CDS_LIB"mstr_standard"
BODY_TYPE"PLUMBING"
HDL_TAP"TRUE";
"B \NAC \NWC"6;
"S \NAC"
BN"1"65;
%"TAP"
"1","(-5850,5400)","2","mstr_standard","I256";
;
CDS_LIB"mstr_standard"
BODY_TYPE"PLUMBING"
HDL_TAP"TRUE";
"B \NAC \NWC"6;
"S \NAC"
BN"5"69;
%"TAP"
"1","(-5850,5600)","2","mstr_standard","I257";
;
CDS_LIB"mstr_standard"
BODY_TYPE"PLUMBING"
HDL_TAP"TRUE";
"B \NAC \NWC"6;
"S \NAC"
BN"3"63;
%"TAP"
"1","(-5850,5500)","2","mstr_standard","I258";
;
CDS_LIB"mstr_standard"
BODY_TYPE"PLUMBING"
HDL_TAP"TRUE";
"B \NAC \NWC"6;
"S \NAC"
BN"4"62;
%"TAP"
"1","(-5850,5200)","2","mstr_standard","I259";
;
CDS_LIB"mstr_standard"
BODY_TYPE"PLUMBING"
HDL_TAP"TRUE";
"B \NAC \NWC"6;
"S \NAC"
BN"7"67;
%"TAP"
"1","(-5850,5300)","2","mstr_standard","I260";
;
CDS_LIB"mstr_standard"
BODY_TYPE"PLUMBING"
HDL_TAP"TRUE";
"B \NAC \NWC"6;
"S \NAC"
BN"6"68;
%"TAP"
"1","(-5650,4900)","2","mstr_standard","I261";
;
CDS_LIB"mstr_standard"
BODY_TYPE"PLUMBING"
HDL_TAP"TRUE";
"B \NAC \NWC"7;
"S \NAC"
BN"0"61;
%"TAP"
"1","(-5650,5050)","2","mstr_standard","I262";
;
CDS_LIB"mstr_standard"
BODY_TYPE"PLUMBING"
HDL_TAP"TRUE";
"B \NAC \NWC"5;
"S \NAC"
BN"9"58;
%"TAP"
"1","(-5650,4800)","2","mstr_standard","I263";
;
CDS_LIB"mstr_standard"
BODY_TYPE"PLUMBING"
HDL_TAP"TRUE";
"B \NAC \NWC"7;
"S \NAC"
BN"1"60;
%"TAP"
"1","(-5650,4700)","2","mstr_standard","I264";
;
CDS_LIB"mstr_standard"
BODY_TYPE"PLUMBING"
HDL_TAP"TRUE";
"B \NAC \NWC"7;
"S \NAC"
BN"2"59;
%"TAP"
"1","(-5650,4400)","2","mstr_standard","I265";
;
CDS_LIB"mstr_standard"
BODY_TYPE"PLUMBING"
HDL_TAP"TRUE";
"B \NAC \NWC"7;
"S \NAC"
BN"5"55;
%"TAP"
"1","(-5650,4600)","2","mstr_standard","I266";
;
CDS_LIB"mstr_standard"
BODY_TYPE"PLUMBING"
HDL_TAP"TRUE";
"B \NAC \NWC"7;
"S \NAC"
BN"3"57;
%"TAP"
"1","(-5650,4500)","2","mstr_standard","I267";
;
CDS_LIB"mstr_standard"
BODY_TYPE"PLUMBING"
HDL_TAP"TRUE";
"B \NAC \NWC"7;
"S \NAC"
BN"4"56;
%"TAP"
"1","(-5650,4300)","2","mstr_standard","I268";
;
CDS_LIB"mstr_standard"
BODY_TYPE"PLUMBING"
HDL_TAP"TRUE";
"B \NAC \NWC"7;
"S \NAC"
BN"6"54;
%"TAP"
"1","(-5650,4200)","2","mstr_standard","I269";
;
CDS_LIB"mstr_standard"
BODY_TYPE"PLUMBING"
HDL_TAP"TRUE";
"B \NAC \NWC"7;
"S \NAC"
BN"7"53;
%"TAP"
"1","(-5650,4100)","2","mstr_standard","I270";
;
CDS_LIB"mstr_standard"
BODY_TYPE"PLUMBING"
HDL_TAP"TRUE";
"B \NAC \NWC"7;
"S \NAC"
BN"8"52;
%"TAP"
"1","(-5850,5100)","2","mstr_standard","I271";
;
CDS_LIB"mstr_standard"
BODY_TYPE"PLUMBING"
HDL_TAP"TRUE";
"B \NAC \NWC"6;
"S \NAC"
BN"8"48;
%"TAP"
"1","(-5850,5000)","2","mstr_standard","I272";
;
CDS_LIB"mstr_standard"
BODY_TYPE"PLUMBING"
HDL_TAP"TRUE";
"B \NAC \NWC"6;
"S \NAC"
BN"9"46;
%"TAP"
"1","(-5850,4850)","2","mstr_standard","I273";
;
CDS_LIB"mstr_standard"
BODY_TYPE"PLUMBING"
HDL_TAP"TRUE";
"B \NAC \NWC"8;
"S \NAC"
BN"0"51;
%"TAP"
"1","(-5850,4650)","2","mstr_standard","I274";
;
CDS_LIB"mstr_standard"
BODY_TYPE"PLUMBING"
HDL_TAP"TRUE";
"B \NAC \NWC"8;
"S \NAC"
BN"2"49;
%"TAP"
"1","(-5850,4750)","2","mstr_standard","I275";
;
CDS_LIB"mstr_standard"
BODY_TYPE"PLUMBING"
HDL_TAP"TRUE";
"B \NAC \NWC"8;
"S \NAC"
BN"1"50;
%"TAP"
"1","(-5850,4450)","2","mstr_standard","I276";
;
CDS_LIB"mstr_standard"
BODY_TYPE"PLUMBING"
HDL_TAP"TRUE";
"B \NAC \NWC"8;
"S \NAC"
BN"4"45;
%"TAP"
"1","(-5850,4550)","2","mstr_standard","I277";
;
CDS_LIB"mstr_standard"
BODY_TYPE"PLUMBING"
HDL_TAP"TRUE";
"B \NAC \NWC"8;
"S \NAC"
BN"3"47;
%"TAP"
"1","(-5850,4350)","2","mstr_standard","I278";
;
CDS_LIB"mstr_standard"
BODY_TYPE"PLUMBING"
HDL_TAP"TRUE";
"B \NAC \NWC"8;
"S \NAC"
BN"5"44;
%"TAP"
"1","(-5850,4250)","2","mstr_standard","I279";
;
CDS_LIB"mstr_standard"
BODY_TYPE"PLUMBING"
HDL_TAP"TRUE";
"B \NAC \NWC"8;
"S \NAC"
BN"6"43;
%"TAP"
"1","(-5850,4150)","2","mstr_standard","I280";
;
CDS_LIB"mstr_standard"
BODY_TYPE"PLUMBING"
HDL_TAP"TRUE";
"B \NAC \NWC"8;
"S \NAC"
BN"7"42;
%"TAP"
"1","(-5650,4000)","2","mstr_standard","I285";
;
CDS_LIB"mstr_standard"
BODY_TYPE"PLUMBING"
HDL_TAP"TRUE";
"B \NAC \NWC"7;
"S \NAC"
BN"9"41;
%"TAP"
"1","(-5850,3950)","2","mstr_standard","I286";
;
CDS_LIB"mstr_standard"
BODY_TYPE"PLUMBING"
HDL_TAP"TRUE";
"B \NAC \NWC"8;
"S \NAC"
BN"9"25;
%"TAP"
"1","(-5850,4050)","2","mstr_standard","I287";
;
CDS_LIB"mstr_standard"
BODY_TYPE"PLUMBING"
HDL_TAP"TRUE";
"B \NAC \NWC"8;
"S \NAC"
BN"8"26;
%"TAP"
"1","(-5850,3750)","2","mstr_standard","I288";
;
CDS_LIB"mstr_standard"
BODY_TYPE"PLUMBING"
HDL_TAP"TRUE";
"B \NAC \NWC"9;
"S \NAC"
BN"1"38;
%"TAP"
"1","(-5850,3800)","2","mstr_standard","I289";
;
CDS_LIB"mstr_standard"
BODY_TYPE"PLUMBING"
HDL_TAP"TRUE";
"B \NAC \NWC"9;
"S \NAC"
BN"0"40;
%"TAP"
"1","(-5850,3700)","2","mstr_standard","I290";
;
CDS_LIB"mstr_standard"
BODY_TYPE"PLUMBING"
HDL_TAP"TRUE";
"B \NAC \NWC"9;
"S \NAC"
BN"2"36;
%"TAP"
"1","(-5850,3650)","2","mstr_standard","I291";
;
CDS_LIB"mstr_standard"
BODY_TYPE"PLUMBING"
HDL_TAP"TRUE";
"B \NAC \NWC"9;
"S \NAC"
BN"3"34;
%"TAP"
"1","(-5850,3600)","2","mstr_standard","I292";
;
CDS_LIB"mstr_standard"
BODY_TYPE"PLUMBING"
HDL_TAP"TRUE";
"B \NAC \NWC"9;
"S \NAC"
BN"4"32;
%"TAP"
"1","(-5850,3400)","2","mstr_standard","I293";
;
CDS_LIB"mstr_standard"
BODY_TYPE"PLUMBING"
HDL_TAP"TRUE";
"B \NAC \NWC"10;
"S \NAC"
BN"0"39;
%"TAP"
"1","(-5850,3350)","2","mstr_standard","I294";
;
CDS_LIB"mstr_standard"
BODY_TYPE"PLUMBING"
HDL_TAP"TRUE";
"B \NAC \NWC"10;
"S \NAC"
BN"1"37;
%"TAP"
"1","(-5850,3550)","2","mstr_standard","I295";
;
CDS_LIB"mstr_standard"
BODY_TYPE"PLUMBING"
HDL_TAP"TRUE";
"B \NAC \NWC"9;
"S \NAC"
BN"5"30;
%"TAP"
"1","(-5850,3500)","2","mstr_standard","I296";
;
CDS_LIB"mstr_standard"
BODY_TYPE"PLUMBING"
HDL_TAP"TRUE";
"B \NAC \NWC"9;
"S \NAC"
BN"6"28;
%"TAP"
"1","(-5850,3300)","2","mstr_standard","I297";
;
CDS_LIB"mstr_standard"
BODY_TYPE"PLUMBING"
HDL_TAP"TRUE";
"B \NAC \NWC"10;
"S \NAC"
BN"2"35;
%"TAP"
"1","(-5850,3250)","2","mstr_standard","I298";
;
CDS_LIB"mstr_standard"
BODY_TYPE"PLUMBING"
HDL_TAP"TRUE";
"B \NAC \NWC"10;
"S \NAC"
BN"3"33;
%"TAP"
"1","(-5850,3200)","2","mstr_standard","I299";
;
CDS_LIB"mstr_standard"
BODY_TYPE"PLUMBING"
HDL_TAP"TRUE";
"B \NAC \NWC"10;
"S \NAC"
BN"4"31;
%"TAP"
"1","(-5850,3150)","2","mstr_standard","I300";
;
CDS_LIB"mstr_standard"
BODY_TYPE"PLUMBING"
HDL_TAP"TRUE";
"B \NAC \NWC"10;
"S \NAC"
BN"5"29;
%"TAP"
"1","(-5850,3100)","2","mstr_standard","I301";
;
CDS_LIB"mstr_standard"
BODY_TYPE"PLUMBING"
HDL_TAP"TRUE";
"B \NAC \NWC"10;
"S \NAC"
BN"6"27;
%"Q_RES"
"1","(-6525,2100)","0","pure_quanta","I314";
;
LOCATION"R508"
$SEC"1"
CDS_SEC"1"
PACK_TYPE"0402LF"
TOLERANCE"1%"
VALUE"15"
MATERIAL"CHIP"
WATTAGE"1/16W"
CDS_LIB"pure_quanta"
PART_NUMBER"CS01502FB03";
"B"
$PN"2"12;
"A"
$PN"1"11;
END.
